(kicad_pcb
	(version 20240108)
	(generator "pcbnew")
	(generator_version "8.0")
	(general
		(thickness 1.62)
		(legacy_teardrops no)
	)
	(paper "A4")
	(title_block
		(title "Jetson Orin Baseboard")
		(date "2025-03-12")
		(rev "1.3.4")
		(company "Antmicro Ltd")
		(comment 1 "www.antmicro.com")
		(comment 9 "footprints 393-397 of 677")
	)
	(layers
		(0 "F.Cu" signal)
		(1 "In1.Cu" signal)
		(2 "In2.Cu" signal)
		(3 "In3.Cu" signal)
		(4 "In4.Cu" jumper)
		(5 "In5.Cu" signal)
		(6 "In6.Cu" signal)
		(31 "B.Cu" signal)
		(32 "B.Adhes" user "B.Adhesive")
		(33 "F.Adhes" user "F.Adhesive")
		(34 "B.Paste" user)
		(35 "F.Paste" user)
		(36 "B.SilkS" user "B.Silkscreen")
		(37 "F.SilkS" user "F.Silkscreen")
		(38 "B.Mask" user)
		(39 "F.Mask" user)
		(40 "Dwgs.User" user "User.Drawings")
		(41 "Cmts.User" user "User.Comments")
		(42 "Eco1.User" user "User.Eco1")
		(43 "Eco2.User" user "User.Eco2")
		(44 "Edge.Cuts" user)
		(45 "Margin" user)
		(46 "B.CrtYd" user "B.Courtyard")
		(47 "F.CrtYd" user "F.Courtyard")
		(48 "B.Fab" user)
		(49 "F.Fab" user)
	)
	(footprint "antmicro-footprints:D_SOD-123F"
		(layer "B.Cu")
		(at 51.2 93.3 180)
		(property "Reference" "D14"
			(at 4.65 1.04 0)
			(layer "B.SilkS")
			(effects
				(font
					(size 0.7 0.7)
					(thickness 0.15)
				)
				(justify left bottom mirror)
			)
		)
		(property "Value" "PTVS58VS1UR,115"
			(at 0 -2.1 0)
			(layer "B.Fab")
			(effects
				(font
					(size 0.7 0.7)
					(thickness 0.15)
				)
				(justify left bottom mirror)
			)
		)
		(property "Footprint" "antmicro-footprints:D_SOD-123F"
			(at 0 0 180)
			(layer "F.Fab")
			(hide yes)
			(effects
				(font
					(size 1.27 1.27)
					(thickness 0.15)
				)
			)
		)
		(property "Datasheet" "https://assets.nexperia.com/documents/data-sheet/PTVSXS1UR_SER.pdf"
			(at 0 0 180)
			(layer "F.Fab")
			(hide yes)
			(effects
				(font
					(size 1.27 1.27)
					(thickness 0.15)
				)
			)
		)
		(property "Author" "Antmicro"
			(at 102.4 186.6 0)
			(layer "B.Fab")
			(hide yes)
			(effects
				(font
					(size 1 1)
					(thickness 0.15)
				)
				(justify mirror)
			)
		)
		(property "License" "Apache-2.0"
			(at 102.4 186.6 0)
			(layer "B.Fab")
			(hide yes)
			(effects
				(font
					(size 1 1)
					(thickness 0.15)
				)
				(justify mirror)
			)
		)
		(property "MPN" "PTVS58VS1UR,115"
			(at 102.4 186.6 0)
			(layer "B.Fab")
			(hide yes)
			(effects
				(font
					(size 1 1)
					(thickness 0.15)
				)
				(justify mirror)
			)
		)
		(property "Manufacturer" "Nexperia"
			(at 102.4 186.6 0)
			(layer "B.Fab")
			(hide yes)
			(effects
				(font
					(size 1 1)
					(thickness 0.15)
				)
				(justify mirror)
			)
		)
		(sheetname "Ethernet")
		(sheetfile "ethernet.kicad_sch")
		(attr smd)
		(fp_line
			(start -0.65 -0.6)
			(end -0.65 0.6)
			(stroke
				(width 0.15)
				(type solid)
			)
			(layer "B.SilkS")
		)
		(fp_line
			(start 2.2 -1.1)
			(end 2.2 1.1)
			(stroke
				(width 0.05)
				(type solid)
			)
			(layer "B.CrtYd")
		)
		(fp_line
			(start -2.21 1.1)
			(end 2.2 1.1)
			(stroke
				(width 0.05)
				(type solid)
			)
			(layer "B.CrtYd")
		)
		(fp_line
			(start -2.21 1.1)
			(end -2.21 -1.1)
			(stroke
				(width 0.05)
				(type solid)
			)
			(layer "B.CrtYd")
		)
		(fp_line
			(start -2.21 -1.1)
			(end 2.2 -1.1)
			(stroke
				(width 0.05)
				(type solid)
			)
			(layer "B.CrtYd")
		)
		(fp_line
			(start -0.8 -0.8)
			(end -0.8 0.8)
			(stroke
				(width 0.1)
				(type solid)
			)
			(layer "B.Fab")
		)
		(fp_rect
			(start -1.75 0.802)
			(end 1.749 -0.8)
			(stroke
				(width 0.1)
				(type solid)
			)
			(fill none)
			(layer "B.Fab")
		)
		(fp_text user "Author: Antmicro"
			(at -2.202 -4.998 0)
			(layer "B.Fab")
			(hide yes)
			(effects
				(font
					(size 0.7 0.7)
					(thickness 0.15)
				)
				(justify left bottom mirror)
			)
		)
		(fp_text user "License: Apache-2.0"
			(at -2.202 -6.2 0)
			(layer "B.Fab")
			(hide yes)
			(effects
				(font
					(size 0.7 0.7)
					(thickness 0.15)
				)
				(justify left bottom mirror)
			)
		)
		(fp_text user "${REFERENCE}"
			(at -2.202 -3.798 0)
			(layer "B.Fab")
			(hide yes)
			(effects
				(font
					(size 0.7 0.7)
					(thickness 0.15)
				)
				(justify left bottom mirror)
			)
		)
		(pad "1" smd roundrect
			(at -1.401 0 180)
			(size 1.2 1.2)
			(layers "B.Cu" "B.Paste" "B.Mask")
			(roundrect_rratio 0.25)
			(net 105 "/Ethernet/VDD")
			(pinfunction "C")
			(pintype "passive")
		)
		(pad "2" smd roundrect
			(at 1.398 0 180)
			(size 1.2 1.2)
			(layers "B.Cu" "B.Paste" "B.Mask")
			(roundrect_rratio 0.25)
			(net 499 "/Ethernet/VSS")
			(pinfunction "A")
			(pintype "passive")
		)
	)
	(footprint "antmicro-footprints:TP_SMD_0.75mm"
		(layer "B.Cu")
		(at 68.165 124.57)
		(property "Reference" "TP52"
			(at 4.9 0.15 180)
			(layer "B.SilkS")
			(hide yes)
			(effects
				(font
					(size 0.7 0.7)
					(thickness 0.15)
				)
				(justify left bottom mirror)
			)
		)
		(property "Value" "TP_0.75mm_SMD"
			(at 0 -1.2 180)
			(layer "B.Fab")
			(effects
				(font
					(size 0.7 0.7)
					(thickness 0.15)
				)
				(justify left bottom mirror)
			)
		)
		(property "Footprint" "antmicro-footprints:TP_SMD_0.75mm"
			(at 0 0 0)
			(layer "F.Fab")
			(hide yes)
			(effects
				(font
					(size 1.27 1.27)
					(thickness 0.15)
				)
			)
		)
		(property "Author" "Antmicro"
			(at 0 0 0)
			(layer "B.Fab")
			(hide yes)
			(effects
				(font
					(size 1 1)
					(thickness 0.15)
				)
				(justify mirror)
			)
		)
		(property "License" "Apache-2.0"
			(at 0 0 0)
			(layer "B.Fab")
			(hide yes)
			(effects
				(font
					(size 1 1)
					(thickness 0.15)
				)
				(justify mirror)
			)
		)
		(property "MPN" ""
			(at 0 0 0)
			(layer "B.Fab")
			(hide yes)
			(effects
				(font
					(size 1 1)
					(thickness 0.15)
				)
				(justify mirror)
			)
		)
		(property "Manufacturer" ""
			(at 0 0 0)
			(layer "B.Fab")
			(hide yes)
			(effects
				(font
					(size 1 1)
					(thickness 0.15)
				)
				(justify mirror)
			)
		)
		(sheetname "Supply")
		(sheetfile "supply.kicad_sch")
		(attr exclude_from_pos_files exclude_from_bom)
		(fp_circle
			(center 0 0)
			(end 0.475 0)
			(stroke
				(width 0.05)
				(type default)
			)
			(fill none)
			(layer "B.CrtYd")
		)
		(fp_text user "${REFERENCE}"
			(at -0.4 -2.7 180)
			(layer "B.Fab")
			(hide yes)
			(effects
				(font
					(size 0.7 0.7)
					(thickness 0.15)
				)
				(justify left bottom mirror)
			)
		)
		(fp_text user "Author: Antmicro"
			(at -0.4 -3.901 180)
			(layer "B.Fab")
			(hide yes)
			(effects
				(font
					(size 0.7 0.7)
					(thickness 0.15)
				)
				(justify left bottom mirror)
			)
		)
		(fp_text user "License: Apache-2.0"
			(at -0.4 -5.101 180)
			(layer "B.Fab")
			(hide yes)
			(effects
				(font
					(size 0.7 0.7)
					(thickness 0.15)
				)
				(justify left bottom mirror)
			)
		)
		(pad "1" smd circle
			(at 0 0)
			(size 0.75 0.75)
			(layers "B.Cu" "B.Mask")
			(net 117 "3V3_STDB")
			(pinfunction "1")
			(pintype "passive")
		)
	)
	(footprint "antmicro-footprints:C_0805_2012Metric"
		(layer "B.Cu")
		(at 51.3 95.45)
		(descr "Capacitor SMD 0805")
		(tags "capacitor SMD 0805")
		(property "Reference" "C76"
			(at -1 1.87 0)
			(layer "B.SilkS")
			(effects
				(font
					(size 0.7 0.7)
					(thickness 0.15)
				)
				(justify right bottom mirror)
			)
		)
		(property "Value" "C_100n_100V_0805"
			(at -2.055717 -1.963152 0)
			(layer "B.Fab")
			(effects
				(font
					(size 0.7 0.7)
					(thickness 0.15)
				)
				(justify right bottom mirror)
			)
		)
		(property "Footprint" "antmicro-footprints:C_0805_2012Metric"
			(at 0 0 0)
			(layer "F.Fab")
			(hide yes)
			(effects
				(font
					(size 1.27 1.27)
					(thickness 0.15)
				)
			)
		)
		(property "Datasheet" "https://product.samsungsem.com/mlcc/CL21B104KCFNNN.do"
			(at 0 0 0)
			(layer "F.Fab")
			(hide yes)
			(effects
				(font
					(size 1.27 1.27)
					(thickness 0.15)
				)
			)
		)
		(property "Author" "Antmicro"
			(at 0 0 0)
			(layer "B.Fab")
			(hide yes)
			(effects
				(font
					(size 1 1)
					(thickness 0.15)
				)
				(justify mirror)
			)
		)
		(property "Dielectric" "X7R"
			(at 0 0 0)
			(layer "B.Fab")
			(hide yes)
			(effects
				(font
					(size 1 1)
					(thickness 0.15)
				)
				(justify mirror)
			)
		)
		(property "License" "Apache-2.0"
			(at 0 0 0)
			(layer "B.Fab")
			(hide yes)
			(effects
				(font
					(size 1 1)
					(thickness 0.15)
				)
				(justify mirror)
			)
		)
		(property "MPN" "CL21B104KCFNNNE"
			(at 0 0 0)
			(layer "B.Fab")
			(hide yes)
			(effects
				(font
					(size 1 1)
					(thickness 0.15)
				)
				(justify mirror)
			)
		)
		(property "Manufacturer" "Samsung Electro-Mechanics"
			(at 0 0 0)
			(layer "B.Fab")
			(hide yes)
			(effects
				(font
					(size 1 1)
					(thickness 0.15)
				)
				(justify mirror)
			)
		)
		(property "Public" "False"
			(at 0 0 0)
			(layer "B.Fab")
			(hide yes)
			(effects
				(font
					(size 1 1)
					(thickness 0.15)
				)
				(justify mirror)
			)
		)
		(property "Val" "100n"
			(at 0 0 0)
			(layer "B.Fab")
			(hide yes)
			(effects
				(font
					(size 1 1)
					(thickness 0.15)
				)
				(justify mirror)
			)
		)
		(property "Voltage" "100V"
			(at 0 0 0)
			(layer "B.Fab")
			(hide yes)
			(effects
				(font
					(size 1 1)
					(thickness 0.15)
				)
				(justify mirror)
			)
		)
		(sheetname "Ethernet")
		(sheetfile "ethernet.kicad_sch")
		(attr smd)
		(fp_line
			(start 0.3 -0.7)
			(end -0.3 -0.7)
			(stroke
				(width 0.15)
				(type solid)
			)
			(layer "B.SilkS")
		)
		(fp_line
			(start 0.3 0.7)
			(end -0.3 0.7)
			(stroke
				(width 0.15)
				(type solid)
			)
			(layer "B.SilkS")
		)
		(fp_rect
			(start 1.95 0.9)
			(end -1.95 -0.9)
			(stroke
				(width 0.05)
				(type default)
			)
			(fill none)
			(layer "B.CrtYd")
		)
		(fp_rect
			(start -0.95 0.675)
			(end 0.95 -0.675)
			(stroke
				(width 0.15)
				(type solid)
			)
			(fill none)
			(layer "B.Fab")
		)
		(fp_text user "License: Apache-2.0"
			(at -1.9 -4.947 0)
			(layer "B.Fab")
			(hide yes)
			(effects
				(font
					(size 0.7 0.7)
					(thickness 0.15)
				)
				(justify right bottom mirror)
			)
		)
		(fp_text user "Author: Antmicro"
			(at -1.9 -5.947 0)
			(layer "B.Fab")
			(hide yes)
			(effects
				(font
					(size 0.7 0.7)
					(thickness 0.15)
				)
				(justify right bottom mirror)
			)
		)
		(fp_text user "${REFERENCE}"
			(at -1.9 -3.947 0)
			(layer "B.Fab")
			(hide yes)
			(effects
				(font
					(size 0.7 0.7)
					(thickness 0.15)
				)
				(justify right bottom mirror)
			)
		)
		(pad "1" smd roundrect
			(at -1.1 0)
			(size 1.2 1.3)
			(layers "B.Cu" "B.Paste" "B.Mask")
			(roundrect_rratio 0.25)
			(net 499 "/Ethernet/VSS")
			(pintype "passive")
		)
		(pad "2" smd roundrect
			(at 1.1 0)
			(size 1.2 1.3)
			(layers "B.Cu" "B.Paste" "B.Mask")
			(roundrect_rratio 0.25)
			(net 105 "/Ethernet/VDD")
			(pintype "passive")
		)
	)
	(footprint "antmicro-footprints:R_Array_4x0201_Panasonic_EXB18V"
		(layer "B.Cu")
		(at 90.135 106.25)
		(property "Reference" "R25"
			(at -1.085 1.45 180)
			(layer "B.SilkS")
			(effects
				(font
					(size 0.7 0.7)
					(thickness 0.15)
				)
				(justify right bottom mirror)
			)
		)
		(property "Value" "R_4x0R_0201_array"
			(at -1.1 -1.8 180)
			(layer "B.Fab")
			(effects
				(font
					(size 0.7 0.7)
					(thickness 0.15)
				)
				(justify left bottom mirror)
			)
		)
		(property "Footprint" "antmicro-footprints:R_Array_4x0201_Panasonic_EXB18V"
			(at 0 0 0)
			(layer "F.Fab")
			(hide yes)
			(effects
				(font
					(size 1.27 1.27)
					(thickness 0.15)
				)
			)
		)
		(property "Datasheet" "http://industrial.panasonic.com/cdbs/www-data/pdf/AOC0000/AOC0000C14.pdf"
			(at 0 0 0)
			(layer "F.Fab")
			(hide yes)
			(effects
				(font
					(size 1.27 1.27)
					(thickness 0.15)
				)
			)
		)
		(property "Author" "Antmicro"
			(at 0 0 0)
			(layer "B.Fab")
			(hide yes)
			(effects
				(font
					(size 1 1)
					(thickness 0.15)
				)
				(justify mirror)
			)
		)
		(property "License" "Apache-2.0"
			(at 0 0 0)
			(layer "B.Fab")
			(hide yes)
			(effects
				(font
					(size 1 1)
					(thickness 0.15)
				)
				(justify mirror)
			)
		)
		(property "MPN" "EXB-18VR000X"
			(at 0 0 0)
			(layer "B.Fab")
			(hide yes)
			(effects
				(font
					(size 1 1)
					(thickness 0.15)
				)
				(justify mirror)
			)
		)
		(property "Manufacturer" "Panasonic"
			(at 0 0 0)
			(layer "B.Fab")
			(hide yes)
			(effects
				(font
					(size 1 1)
					(thickness 0.15)
				)
				(justify mirror)
			)
		)
		(property "Val" "4x0R_0201"
			(at 0 0 0)
			(layer "B.Fab")
			(hide yes)
			(effects
				(font
					(size 1 1)
					(thickness 0.15)
				)
				(justify mirror)
			)
		)
		(sheetname "Peripherals")
		(sheetfile "peripherals.kicad_sch")
		(attr smd)
		(fp_line
			(start -0.8 -0.45)
			(end -0.8 0.45)
			(stroke
				(width 0.12)
				(type solid)
			)
			(layer "B.SilkS")
		)
		(fp_line
			(start 0.8 -0.45)
			(end 0.8 0.45)
			(stroke
				(width 0.12)
				(type solid)
			)
			(layer "B.SilkS")
		)
		(fp_rect
			(start -0.898 0.66)
			(end 0.898 -0.65)
			(stroke
				(width 0.05)
				(type solid)
			)
			(fill none)
			(layer "B.CrtYd")
		)
		(fp_text user "License: Apache-2.0"
			(at -1.051 -6 180)
			(layer "B.Fab")
			(hide yes)
			(effects
				(font
					(size 0.7 0.7)
					(thickness 0.15)
				)
				(justify left bottom mirror)
			)
		)
		(fp_text user "Author: Antmicro"
			(at -1.051 -4.599 180)
			(layer "B.Fab")
			(hide yes)
			(effects
				(font
					(size 0.7 0.7)
					(thickness 0.15)
				)
				(justify left bottom mirror)
			)
		)
		(fp_text user "${REFERENCE}"
			(at -1.051 -3.2 180)
			(layer "B.Fab")
			(hide yes)
			(effects
				(font
					(size 0.7 0.7)
					(thickness 0.15)
				)
				(justify left bottom mirror)
			)
		)
		(pad "1" smd roundrect
			(at -0.6 -0.298)
			(size 0.2 0.4)
			(layers "B.Cu" "B.Paste" "B.Mask")
			(roundrect_rratio 0.25)
			(net 322 "CSIA_PEN")
			(pinfunction "R1.1")
			(pintype "passive")
		)
		(pad "2" smd roundrect
			(at -0.202 -0.298)
			(size 0.2 0.4)
			(layers "B.Cu" "B.Paste" "B.Mask")
			(roundrect_rratio 0.25)
			(net 338 "CSIB_PEN")
			(pinfunction "R2.1")
			(pintype "passive")
		)
		(pad "3" smd roundrect
			(at 0.2 -0.298)
			(size 0.2 0.4)
			(layers "B.Cu" "B.Paste" "B.Mask")
			(roundrect_rratio 0.25)
			(net 562 "USBC1_PEN")
			(pinfunction "R3.1")
			(pintype "passive")
		)
		(pad "4" smd roundrect
			(at 0.598 -0.298)
			(size 0.2 0.4)
			(layers "B.Cu" "B.Paste" "B.Mask")
			(roundrect_rratio 0.25)
			(net 514 "DISABLE_POE_DCDC")
			(pinfunction "R4.1")
			(pintype "passive")
		)
		(pad "5" smd roundrect
			(at 0.598 0.3)
			(size 0.2 0.4)
			(layers "B.Cu" "B.Paste" "B.Mask")
			(roundrect_rratio 0.25)
			(net 356 "/Peripherals/GPIOEX_P0_3")
			(pinfunction "R4.2")
			(pintype "passive")
		)
		(pad "6" smd roundrect
			(at 0.2 0.3)
			(size 0.2 0.4)
			(layers "B.Cu" "B.Paste" "B.Mask")
			(roundrect_rratio 0.25)
			(net 355 "/Peripherals/GPIOEX_P0_2")
			(pinfunction "R3.2")
			(pintype "passive")
		)
		(pad "7" smd roundrect
			(at -0.202 0.3)
			(size 0.2 0.4)
			(layers "B.Cu" "B.Paste" "B.Mask")
			(roundrect_rratio 0.25)
			(net 354 "/Peripherals/GPIOEX_P0_1")
			(pinfunction "R2.2")
			(pintype "passive")
		)
		(pad "8" smd roundrect
			(at -0.6 0.3)
			(size 0.2 0.4)
			(layers "B.Cu" "B.Paste" "B.Mask")
			(roundrect_rratio 0.25)
			(net 353 "/Peripherals/GPIOEX_P0_0")
			(pinfunction "R1.2")
			(pintype "passive")
		)
	)
	(footprint "antmicro-footprints:SOD-923"
		(layer "B.Cu")
		(at 56.5 119.67)
		(property "Reference" "D6"
			(at 0.8 -0.52 0)
			(unlocked yes)
			(layer "B.SilkS")
			(effects
				(font
					(size 0.7 0.7)
					(thickness 0.15)
				)
				(justify left bottom mirror)
			)
		)
		(property "Value" "DF2S30FS_SOD"
			(at 0 -1.3 180)
			(unlocked yes)
			(layer "B.Fab")
			(effects
				(font
					(size 0.7 0.7)
					(thickness 0.15)
				)
				(justify left bottom mirror)
			)
		)
		(property "Footprint" "antmicro-footprints:SOD-923"
			(at 0 0 0)
			(layer "F.Fab")
			(hide yes)
			(effects
				(font
					(size 1.27 1.27)
					(thickness 0.15)
				)
			)
		)
		(property "Datasheet" "https://toshiba.semicon-storage.com/info/DF2S30FS_datasheet_en_20211216.pdf?did=11156&prodName=DF2S30FS"
			(at 0 0 0)
			(layer "F.Fab")
			(hide yes)
			(effects
				(font
					(size 1.27 1.27)
					(thickness 0.15)
				)
			)
		)
		(property "Author" "Antmicro"
			(at 0 0 0)
			(layer "B.Fab")
			(hide yes)
			(effects
				(font
					(size 1 1)
					(thickness 0.15)
				)
				(justify mirror)
			)
		)
		(property "License" "Apache-2.0"
			(at 0 0 0)
			(layer "B.Fab")
			(hide yes)
			(effects
				(font
					(size 1 1)
					(thickness 0.15)
				)
				(justify mirror)
			)
		)
		(property "MPN" "DF2S30FS"
			(at 0 0 0)
			(layer "B.Fab")
			(hide yes)
			(effects
				(font
					(size 1 1)
					(thickness 0.15)
				)
				(justify mirror)
			)
		)
		(property "Manufacturer" "Toshiba"
			(at 0 0 0)
			(layer "B.Fab")
			(hide yes)
			(effects
				(font
					(size 1 1)
					(thickness 0.15)
				)
				(justify mirror)
			)
		)
		(sheetname "USB Debug, DP")
		(sheetfile "usb.kicad_sch")
		(attr smd)
		(fp_line
			(start -0.5 -0.3)
			(end -0.5 -0.4)
			(stroke
				(width 0.15)
				(type solid)
			)
			(layer "B.SilkS")
		)
		(fp_line
			(start -0.5 0.4)
			(end -0.5 0.3)
			(stroke
				(width 0.15)
				(type solid)
			)
			(layer "B.SilkS")
		)
		(fp_line
			(start -0.16 -0.4)
			(end -0.16 0.4)
			(stroke
				(width 0.15)
				(type solid)
			)
			(layer "B.SilkS")
		)
		(fp_line
			(start 0.5 -0.4)
			(end -0.5 -0.4)
			(stroke
				(width 0.15)
				(type solid)
			)
			(layer "B.SilkS")
		)
		(fp_line
			(start 0.5 -0.3)
			(end 0.5 -0.4)
			(stroke
				(width 0.15)
				(type solid)
			)
			(layer "B.SilkS")
		)
		(fp_line
			(start 0.5 0.3)
			(end 0.5 0.4)
			(stroke
				(width 0.15)
				(type solid)
			)
			(layer "B.SilkS")
		)
		(fp_line
			(start 0.5 0.4)
			(end -0.5 0.4)
			(stroke
				(width 0.15)
				(type solid)
			)
			(layer "B.SilkS")
		)
		(fp_rect
			(start -0.68 0.41)
			(end 0.68 -0.41)
			(stroke
				(width 0.05)
				(type solid)
			)
			(fill none)
			(layer "B.CrtYd")
		)
		(fp_line
			(start -0.202 -0.298)
			(end -0.202 0.3)
			(stroke
				(width 0.15)
				(type solid)
			)
			(layer "B.Fab")
		)
		(fp_rect
			(start -0.402 0.3)
			(end 0.4 -0.298)
			(stroke
				(width 0.15)
				(type solid)
			)
			(fill none)
			(layer "B.Fab")
		)
		(fp_text user "License: Apache-2.0"
			(at -0.68 -4.5 180)
			(layer "B.Fab")
			(hide yes)
			(effects
				(font
					(size 0.7 0.7)
					(thickness 0.15)
				)
				(justify left bottom mirror)
			)
		)
		(fp_text user "Author: Antmicro"
			(at -0.68 -5.7 180)
			(layer "B.Fab")
			(hide yes)
			(effects
				(font
					(size 0.7 0.7)
					(thickness 0.15)
				)
				(justify left bottom mirror)
			)
		)
		(fp_text user "${REFERENCE}"
			(at -0.68 -3.3 180)
			(unlocked yes)
			(layer "B.Fab")
			(hide yes)
			(effects
				(font
					(size 0.7 0.7)
					(thickness 0.15)
				)
				(justify left bottom mirror)
			)
		)
		(pad "1" smd roundrect
			(at -0.438 0)
			(size 0.4 0.325)
			(layers "B.Cu" "B.Paste" "B.Mask")
			(roundrect_rratio 0.25)
			(net 196 "/USB Debug, DP/USBC3_VBUS")
			(pinfunction "C")
			(pintype "passive")
		)
		(pad "2" smd roundrect
			(at 0.436 0)
			(size 0.4 0.325)
			(layers "B.Cu" "B.Paste" "B.Mask")
			(roundrect_rratio 0.25)
			(net 1 "GND")
			(pinfunction "A")
			(pintype "passive")
		)
	)
)
